FILE_TYPE = MACRO_DRAWING;
SET COLOR_WIRE YELLOW;
SET COLOR_PROP ORANGE;
SET COLOR_DOT WHITE;
SET COLOR_ARC YELLOW;
SET COLOR_BODY GREEN;
SET COLOR_NOTE PURPLE;
SET PROP_DISPLAY VALUE;
SET PAGE_NUMBER P139;
FORCEADD QUANTA_TITLE_BLOCK_C..1
(-100 100);
FORCEPROP 1 LAST CUSTOM_TXT_CDS <NAME_2>
J 0
(-3275 150);
FORCEPROP 1 LAST CUSTOM_TXT_CDS <NAME_1>
J 0
(-3275 275);
FORCEPROP 1 LAST CUSTOM_TXT_CDS <Q_NUMBER>
J 0
(-1503 203);
DISPLAY 1.212766 (-1503 203);
FORCEPROP 1 LAST CUSTOM_TXT_CDS <Q_PROJ>
J 0
(-2482 202);
DISPLAY 1.212766 (-2482 202);
FORCEPROP 1 LAST CUSTOM_TXT_CDS <Q_REV>
J 0
(-284 203);
DISPLAY 1.212766 (-284 203);
FORCEPROP 1 LAST CUSTOM_TXT_CDS <CON_LAST_MODIFIED>
J 0
(-1985 115);
DISPLAY 0.978723 (-1985 115);
FORCEPROP 1 LAST CUSTOM_TXT_CDS <CON_PAGE_NUM> OF <CON_TOTAL_PAGES>
J 0
(-546 118);
DISPLAY 0.978723 (-546 118);
FORCEPROP 1 LAST Q_TITLE Blank
J 0
(-9350 200);
DISPLAY 2.446809 (-9350 200);
PAINT GREEN (-9350 200);
FORCEPROP 2 LAST PAGE_BORDER TRUE
J 0
(-7990 5350);
DISPLAY 0.638298 (-7990 5350);
PAINT PINK (-7990 5350);
DISPLAY INVISIBLE (-7990 5350);
FORCEPROP 1 LAST CDS_LMAN_SYM_OUTLINE -9475,6775,100,-125
J 0
(-100 100);
DISPLAY 0.468085 (-100 100);
PAINT GREEN (-100 100);
DISPLAY INVISIBLE (-100 100);
FORCEPROP 2 LAST CDS_LIB pure_quanta
J 0
(-100 100);
DISPLAY INVISIBLE (-100 100);
FORCEPROP 2 LAST CDS_XR_PAGE_TITLE CR-162 : @T6G_MB_LIB.T6G(SCH_1):PAGE162
J 0
(-7990 5350);
DISPLAY 0.638298 (-7990 5350);
PAINT PINK (-7990 5350);
DISPLAY INVISIBLE (-7990 5350);
FORCEPROP 2 LAST CUSTOM_TXT_CDS <XR_PAGE_TITLE>
J 0
(-7990 5350);
DISPLAY 0.638298 (-7990 5350);
PAINT PINK (-7990 5350);
DISPLAY INVISIBLE (-7990 5350);
FORCEPROP 1 LAST COMMENT_BODY TRUE
J 0
(-88 87);
DISPLAY 0.978723 (-88 87);
PAINT GREEN (-88 87);
DISPLAY INVISIBLE (-88 87);
FORCEPROP 1 LAST Q_DEPT BU9
J 1
(-3863 149);
DISPLAY 1.957447 (-3863 149);
PAINT GREEN (-3863 149);
DISPLAY INVISIBLE (-3863 149);
FORCEPROP 0 LAST CDS_CON_LAST_MODIFIED Thu Aug 24 10:14:46 2023
J 0
(-1985 115);
DISPLAY INVISIBLE (-1985 115);
QUIT
